(kicad_pcb
	(version 20260206)
	(generator "pcbnew")
	(generator_version "10.0")
	(general
		(thickness 1.6)
		(legacy_teardrops no)
	)
	(paper "A4")
	(title_block
		(title "peb — Lightning_PEB_BRD.brd")
		(comment 1 "Lightning (Wiwynn / Facebook NVMe JBOF) / footprints 1709-1716 of 2563")
	)
	(layers
		(0 "F.Cu" signal "TOP")
		(4 "In1.Cu" signal "L2GND")
		(6 "In2.Cu" signal "L3")
		(8 "In3.Cu" signal "L4VCC")
		(10 "In4.Cu" signal "L5VCC")
		(12 "In5.Cu" signal "L6")
		(14 "In6.Cu" signal "L7GND")
		(2 "B.Cu" signal "BOTTOM")
		(9 "F.Adhes" user "F.Adhesive")
		(11 "B.Adhes" user "B.Adhesive")
		(13 "F.Paste" user "Package Geometry/Pastemask Top")
		(15 "B.Paste" user "Package Geometry/Pastemask Bottom")
		(5 "F.SilkS" user "Ref Des/Silkscreen Top")
		(7 "B.SilkS" user "Ref Des/Silkscreen Bottom")
		(1 "F.Mask" user "Board Geometry/Soldermask Top")
		(3 "B.Mask" user "Board Geometry/Soldermask Bottom")
		(17 "Dwgs.User" user "User.Drawings")
		(19 "Cmts.User" user "User.Comments")
		(21 "Eco1.User" user "User.Eco1")
		(23 "Eco2.User" user "User.Eco2")
		(25 "Edge.Cuts" user "Board Geometry/Outline")
		(27 "Margin" user)
		(31 "F.CrtYd" user "Package Geometry/Place Bound Top")
		(29 "B.CrtYd" user "Package Geometry/Place Bound Bottom")
		(35 "F.Fab" user "Ref Des/Assembly Top")
		(33 "B.Fab" user "Ref Des/Assembly Bottom")
	)
	(footprint ""
		(layer "B.Cu")
		(at 66.548 -150.622 -90)
		(property "Reference" "R212"
			(at 0 0 90)
			(layer "B.SilkS")
			(hide yes)
			(effects
				(font
					(size 1.27 1.27)
				)
				(justify mirror)
			)
		)
		(property "Value" "0R2J-2-GP"
			(at -0.064008 -3.993896 270)
			(unlocked yes)
			(layer "B.Fab")
			(hide yes)
			(effects
				(font
					(size 1.016 1.016)
					(thickness 0.1524)
				)
				(justify mirror)
			)
		)
		(property "Device Type" "R402H16"
			(at -0.064008 -5.517896 270)
			(unlocked yes)
			(layer "B.Fab")
			(hide yes)
			(effects
				(font
					(size 1.016 1.016)
					(thickness 0.1524)
				)
				(justify mirror)
			)
		)
		(duplicate_pad_numbers_are_jumpers no)
		(fp_line
			(start -0.508 -0.9398)
			(end 0.508 -0.9398)
			(stroke
				(width 0.1524)
				(type default)
			)
			(layer "B.SilkS")
		)
		(fp_line
			(start 0.508 -0.9398)
			(end 0.508 0.9398)
			(stroke
				(width 0.1524)
				(type default)
			)
			(layer "B.SilkS")
		)
		(fp_rect
			(start 0.508 0.9398)
			(end -0.508 -0.9398)
			(stroke
				(width 0)
				(type default)
			)
			(fill no)
			(layer "B.CrtYd")
		)
		(fp_rect
			(start 0.508 0.9398)
			(end -0.508 -0.9398)
			(stroke
				(width 0)
				(type default)
			)
			(fill no)
			(layer "B.Fab")
		)
		(pad "1" smd custom
			(at 0 -0.4445 90)
			(size 0.1397 0.1397)
			(layers "B.Cu" "B.Mask" "B.Paste")
			(net "EEPROM_SDA")
			(options
				(clearance outline)
				(anchor circle)
			)
			(primitives
				(gr_poly
					(pts
						(arc
							(start -0.1778 0.2794)
							(mid -0.249642 0.249642)
							(end -0.2794 0.1778)
						)
						(arc
							(start -0.2794 -0.1778)
							(mid -0.249642 -0.249642)
							(end -0.1778 -0.2794)
						)
						(arc
							(start 0.1778 -0.2794)
							(mid 0.249642 -0.249642)
							(end 0.2794 -0.1778)
						)
						(arc
							(start 0.2794 0.1778)
							(mid 0.249642 0.249642)
							(end 0.1778 0.2794)
						)
					)
					(width 0)
					(fill yes)
				)
			)
		)
		(pad "2" smd custom
			(at 0 0.4445 90)
			(size 0.1397 0.1397)
			(layers "B.Cu" "B.Mask" "B.Paste")
			(net "BMC_I2C5_D_PEB_SDA")
			(options
				(clearance outline)
				(anchor circle)
			)
			(primitives
				(gr_poly
					(pts
						(arc
							(start -0.1778 0.2794)
							(mid -0.249642 0.249642)
							(end -0.2794 0.1778)
						)
						(arc
							(start -0.2794 -0.1778)
							(mid -0.249642 -0.249642)
							(end -0.1778 -0.2794)
						)
						(arc
							(start 0.1778 -0.2794)
							(mid 0.249642 -0.249642)
							(end 0.2794 -0.1778)
						)
						(arc
							(start 0.2794 0.1778)
							(mid 0.249642 0.249642)
							(end 0.1778 0.2794)
						)
					)
					(width 0)
					(fill yes)
				)
			)
		)
	)
	(footprint ""
		(layer "B.Cu")
		(at 231.5972 -45.9994 -90)
		(property "Reference" "C499"
			(at 0 0 90)
			(layer "B.SilkS")
			(hide yes)
			(effects
				(font
					(size 1.27 1.27)
				)
				(justify mirror)
			)
		)
		(property "Value" "SCD1U16V1KX-1-GP"
			(at 2.8321 -1.7399 270)
			(unlocked yes)
			(layer "B.Fab")
			(hide yes)
			(effects
				(font
					(size 1.016 1.016)
					(thickness 0.1524)
				)
				(justify mirror)
			)
		)
		(property "Device Type" "C0201H13"
			(at 2.8321 -3.2639 270)
			(unlocked yes)
			(layer "B.Fab")
			(hide yes)
			(effects
				(font
					(size 1.016 1.016)
					(thickness 0.1524)
				)
				(justify mirror)
			)
		)
		(duplicate_pad_numbers_are_jumpers no)
		(fp_rect
			(start 0.2794 0.6477)
			(end -0.2794 -0.6477)
			(stroke
				(width 0)
				(type default)
			)
			(fill no)
			(layer "B.CrtYd")
		)
		(fp_rect
			(start 0.2794 0.6477)
			(end -0.2794 -0.6477)
			(stroke
				(width 0)
				(type default)
			)
			(fill no)
			(layer "B.Fab")
		)
		(pad "1" smd custom
			(at 0 -0.2794 90)
			(size 0.0762 0.0762)
			(layers "B.Cu" "B.Mask" "B.Paste")
			(net "DUT_AVD_PCIE_Q")
			(options
				(clearance outline)
				(anchor circle)
			)
			(primitives
				(gr_poly
					(pts
						(arc
							(start 0.1524 0.127)
							(mid 0.137521 0.162921)
							(end 0.1016 0.1778)
						)
						(arc
							(start -0.1016 0.1778)
							(mid -0.137521 0.162921)
							(end -0.1524 0.127)
						)
						(arc
							(start -0.1524 -0.127)
							(mid -0.137521 -0.162921)
							(end -0.1016 -0.1778)
						)
						(arc
							(start 0.1016 -0.1778)
							(mid 0.137521 -0.162921)
							(end 0.1524 -0.127)
						)
					)
					(width 0)
					(fill yes)
				)
			)
		)
		(pad "2" smd custom
			(at 0 0.2794 90)
			(size 0.0762 0.0762)
			(layers "B.Cu" "B.Mask" "B.Paste")
			(net "GND")
			(options
				(clearance outline)
				(anchor circle)
			)
			(primitives
				(gr_poly
					(pts
						(arc
							(start 0.1524 0.127)
							(mid 0.137521 0.162921)
							(end 0.1016 0.1778)
						)
						(arc
							(start -0.1016 0.1778)
							(mid -0.137521 0.162921)
							(end -0.1524 0.127)
						)
						(arc
							(start -0.1524 -0.127)
							(mid -0.137521 -0.162921)
							(end -0.1016 -0.1778)
						)
						(arc
							(start 0.1016 -0.1778)
							(mid 0.137521 -0.162921)
							(end 0.1524 -0.127)
						)
					)
					(width 0)
					(fill yes)
				)
			)
		)
	)
	(footprint ""
		(layer "B.Cu")
		(at 227.6856 -32.995362 -90)
		(property "Reference" "C565"
			(at 0 0 90)
			(layer "B.SilkS")
			(hide yes)
			(effects
				(font
					(size 1.27 1.27)
				)
				(justify mirror)
			)
		)
		(property "Value" "SCD1U16V1KX-1-GP"
			(at 2.8321 -1.7399 270)
			(unlocked yes)
			(layer "B.Fab")
			(hide yes)
			(effects
				(font
					(size 1.016 1.016)
					(thickness 0.1524)
				)
				(justify mirror)
			)
		)
		(property "Device Type" "C0201H13"
			(at 2.8321 -3.2639 270)
			(unlocked yes)
			(layer "B.Fab")
			(hide yes)
			(effects
				(font
					(size 1.016 1.016)
					(thickness 0.1524)
				)
				(justify mirror)
			)
		)
		(duplicate_pad_numbers_are_jumpers no)
		(fp_rect
			(start 0.2794 0.6477)
			(end -0.2794 -0.6477)
			(stroke
				(width 0)
				(type default)
			)
			(fill no)
			(layer "B.CrtYd")
		)
		(fp_rect
			(start 0.2794 0.6477)
			(end -0.2794 -0.6477)
			(stroke
				(width 0)
				(type default)
			)
			(fill no)
			(layer "B.Fab")
		)
		(pad "1" smd custom
			(at 0 -0.2794 90)
			(size 0.0762 0.0762)
			(layers "B.Cu" "B.Mask" "B.Paste")
			(net "DUT_AVD_PCIE")
			(options
				(clearance outline)
				(anchor circle)
			)
			(primitives
				(gr_poly
					(pts
						(arc
							(start 0.1524 0.127)
							(mid 0.137521 0.162921)
							(end 0.1016 0.1778)
						)
						(arc
							(start -0.1016 0.1778)
							(mid -0.137521 0.162921)
							(end -0.1524 0.127)
						)
						(arc
							(start -0.1524 -0.127)
							(mid -0.137521 -0.162921)
							(end -0.1016 -0.1778)
						)
						(arc
							(start 0.1016 -0.1778)
							(mid 0.137521 -0.162921)
							(end 0.1524 -0.127)
						)
					)
					(width 0)
					(fill yes)
				)
			)
		)
		(pad "2" smd custom
			(at 0 0.2794 90)
			(size 0.0762 0.0762)
			(layers "B.Cu" "B.Mask" "B.Paste")
			(net "GND")
			(options
				(clearance outline)
				(anchor circle)
			)
			(primitives
				(gr_poly
					(pts
						(arc
							(start 0.1524 0.127)
							(mid 0.137521 0.162921)
							(end 0.1016 0.1778)
						)
						(arc
							(start -0.1016 0.1778)
							(mid -0.137521 0.162921)
							(end -0.1524 0.127)
						)
						(arc
							(start -0.1524 -0.127)
							(mid -0.137521 -0.162921)
							(end -0.1016 -0.1778)
						)
						(arc
							(start 0.1016 -0.1778)
							(mid 0.137521 -0.162921)
							(end 0.1524 -0.127)
						)
					)
					(width 0)
					(fill yes)
				)
			)
		)
	)
	(footprint ""
		(layer "B.Cu")
		(at 60.325 -34.036 180)
		(property "Reference" "PR30"
			(at 0 0 0)
			(layer "B.SilkS")
			(hide yes)
			(effects
				(font
					(size 1.27 1.27)
				)
				(justify mirror)
			)
		)
		(property "Value" "100KR2F-L1-GP"
			(at -0.064008 -3.993896 180)
			(unlocked yes)
			(layer "B.Fab")
			(hide yes)
			(effects
				(font
					(size 1.016 1.016)
					(thickness 0.1524)
				)
				(justify mirror)
			)
		)
		(property "Device Type" "R402H16"
			(at -0.064008 -5.517896 180)
			(unlocked yes)
			(layer "B.Fab")
			(hide yes)
			(effects
				(font
					(size 1.016 1.016)
					(thickness 0.1524)
				)
				(justify mirror)
			)
		)
		(duplicate_pad_numbers_are_jumpers no)
		(fp_line
			(start 0.508 -0.9398)
			(end 0.508 0.9398)
			(stroke
				(width 0.1524)
				(type default)
			)
			(layer "B.SilkS")
		)
		(fp_line
			(start -0.508 -0.9398)
			(end 0.508 -0.9398)
			(stroke
				(width 0.1524)
				(type default)
			)
			(layer "B.SilkS")
		)
		(fp_rect
			(start 0.508 0.9398)
			(end -0.508 -0.9398)
			(stroke
				(width 0)
				(type default)
			)
			(fill no)
			(layer "B.CrtYd")
		)
		(fp_rect
			(start 0.508 0.9398)
			(end -0.508 -0.9398)
			(stroke
				(width 0)
				(type default)
			)
			(fill no)
			(layer "B.Fab")
		)
		(pad "1" smd custom
			(at 0 -0.4445)
			(size 0.1397 0.1397)
			(layers "B.Cu" "B.Mask" "B.Paste")
			(net "AGND_P3V3_STBY")
			(options
				(clearance outline)
				(anchor circle)
			)
			(primitives
				(gr_poly
					(pts
						(arc
							(start -0.1778 0.2794)
							(mid -0.249642 0.249642)
							(end -0.2794 0.1778)
						)
						(arc
							(start -0.2794 -0.1778)
							(mid -0.249642 -0.249642)
							(end -0.1778 -0.2794)
						)
						(arc
							(start 0.1778 -0.2794)
							(mid 0.249642 -0.249642)
							(end 0.2794 -0.1778)
						)
						(arc
							(start 0.2794 0.1778)
							(mid 0.249642 0.249642)
							(end 0.1778 0.2794)
						)
					)
					(width 0)
					(fill yes)
				)
			)
		)
		(pad "2" smd custom
			(at 0 0.4445)
			(size 0.1397 0.1397)
			(layers "B.Cu" "B.Mask" "B.Paste")
			(net "P3V3_STBY_MODE")
			(options
				(clearance outline)
				(anchor circle)
			)
			(primitives
				(gr_poly
					(pts
						(arc
							(start -0.1778 0.2794)
							(mid -0.249642 0.249642)
							(end -0.2794 0.1778)
						)
						(arc
							(start -0.2794 -0.1778)
							(mid -0.249642 -0.249642)
							(end -0.1778 -0.2794)
						)
						(arc
							(start 0.1778 -0.2794)
							(mid 0.249642 -0.249642)
							(end 0.2794 -0.1778)
						)
						(arc
							(start 0.2794 0.1778)
							(mid 0.249642 0.249642)
							(end 0.1778 0.2794)
						)
					)
					(width 0)
					(fill yes)
				)
			)
		)
	)
	(footprint ""
		(layer "B.Cu")
		(at 310.007 -67.691 180)
		(property "Reference" "PG64"
			(at 0 0 0)
			(layer "B.SilkS")
			(hide yes)
			(effects
				(font
					(size 1.27 1.27)
				)
				(justify mirror)
			)
		)
		(property "Value" "GAP-CLOSE-PWR-3-GP"
			(at -0.0254 -6.5786 180)
			(unlocked yes)
			(layer "B.Fab")
			(hide yes)
			(effects
				(font
					(size 1.016 1.016)
					(thickness 0.1524)
				)
				(justify mirror)
			)
		)
		(property "Device Type" "GAP-CLOSE-PWR-3"
			(at -0.0254 -8.255 180)
			(unlocked yes)
			(layer "B.Fab")
			(hide yes)
			(effects
				(font
					(size 1.016 1.016)
					(thickness 0.1524)
				)
				(justify mirror)
			)
		)
		(duplicate_pad_numbers_are_jumpers no)
		(fp_rect
			(start 0.7112 0.4572)
			(end -0.7112 -0.4572)
			(stroke
				(width 0)
				(type default)
			)
			(fill no)
			(layer "B.CrtYd")
		)
		(fp_poly
			(pts
				(xy 0.7112 -0.4572) (xy -0.7112 -0.4572) (xy -0.7112 0.4572) (xy 0.7112 0.4572)
			)
			(stroke
				(width 0)
				(type default)
			)
			(fill no)
			(layer "B.Fab")
		)
		(pad "1" smd rect
			(at 0.3048 0)
			(size 0.6604 0.762)
			(layers "B.Cu" "B.Mask" "B.Paste")
			(net "DUT_VDD")
		)
		(pad "2" smd rect
			(at -0.3048 0)
			(size 0.6604 0.762)
			(layers "B.Cu" "B.Mask" "B.Paste")
			(net "P0V9_E")
		)
	)
	(footprint ""
		(layer "B.Cu")
		(at 334.2386 -67.691 -90)
		(property "Reference" "PC185"
			(at 0 0 90)
			(layer "B.SilkS")
			(hide yes)
			(effects
				(font
					(size 1.27 1.27)
				)
				(justify mirror)
			)
		)
		(property "Value" "SCD1U50V3KX-GP"
			(at 0 -2.8194 270)
			(unlocked yes)
			(layer "B.Fab")
			(hide yes)
			(effects
				(font
					(size 1.016 1.016)
					(thickness 0.1524)
				)
				(justify mirror)
			)
		)
		(property "Device Type" "C603H36"
			(at 0 -4.3434 270)
			(unlocked yes)
			(layer "B.Fab")
			(hide yes)
			(effects
				(font
					(size 1.016 1.016)
					(thickness 0.1524)
				)
				(justify mirror)
			)
		)
		(duplicate_pad_numbers_are_jumpers no)
		(fp_line
			(start -0.508 0)
			(end 0.508 0)
			(stroke
				(width 0.2032)
				(type default)
			)
			(layer "B.SilkS")
		)
		(fp_rect
			(start 0.5842 1.3335)
			(end -0.5842 -1.3335)
			(stroke
				(width 0)
				(type default)
			)
			(fill no)
			(layer "B.CrtYd")
		)
		(fp_rect
			(start 0.5842 1.3335)
			(end -0.5842 -1.3335)
			(stroke
				(width 0)
				(type default)
			)
			(fill no)
			(layer "B.Fab")
		)
		(pad "1" smd custom
			(at 0 -0.762 90)
			(size 0.2159 0.2159)
			(layers "B.Cu" "B.Mask" "B.Paste")
			(net "P0V9_E_VBST")
			(options
				(clearance outline)
				(anchor circle)
			)
			(primitives
				(gr_poly
					(pts
						(arc
							(start -0.3302 0.4318)
							(mid -0.402042 0.402042)
							(end -0.4318 0.3302)
						)
						(arc
							(start -0.4318 -0.3302)
							(mid -0.402042 -0.402042)
							(end -0.3302 -0.4318)
						)
						(arc
							(start 0.3302 -0.4318)
							(mid 0.402042 -0.402042)
							(end 0.4318 -0.3302)
						)
						(arc
							(start 0.4318 0.3302)
							(mid 0.402042 0.402042)
							(end 0.3302 0.4318)
						)
					)
					(width 0)
					(fill yes)
				)
			)
		)
		(pad "2" smd custom
			(at 0 0.762 90)
			(size 0.2159 0.2159)
			(layers "B.Cu" "B.Mask" "B.Paste")
			(net "P0V9_E_VBST_RC")
			(options
				(clearance outline)
				(anchor circle)
			)
			(primitives
				(gr_poly
					(pts
						(arc
							(start -0.3302 0.4318)
							(mid -0.402042 0.402042)
							(end -0.4318 0.3302)
						)
						(arc
							(start -0.4318 -0.3302)
							(mid -0.402042 -0.402042)
							(end -0.3302 -0.4318)
						)
						(arc
							(start 0.3302 -0.4318)
							(mid 0.402042 -0.402042)
							(end 0.4318 -0.3302)
						)
						(arc
							(start 0.4318 0.3302)
							(mid 0.402042 0.402042)
							(end 0.3302 0.4318)
						)
					)
					(width 0)
					(fill yes)
				)
			)
		)
	)
	(footprint ""
		(layer "B.Cu")
		(at 129.179066 -208.8769 180)
		(property "Reference" "R4127"
			(at 0 0 0)
			(layer "B.SilkS")
			(hide yes)
			(effects
				(font
					(size 1.27 1.27)
				)
				(justify mirror)
			)
		)
		(property "Value" "4K7R2F-GP"
			(at -0.064008 -3.993896 180)
			(unlocked yes)
			(layer "B.Fab")
			(hide yes)
			(effects
				(font
					(size 1.016 1.016)
					(thickness 0.1524)
				)
				(justify mirror)
			)
		)
		(property "Device Type" "R402H16"
			(at -0.064008 -5.517896 180)
			(unlocked yes)
			(layer "B.Fab")
			(hide yes)
			(effects
				(font
					(size 1.016 1.016)
					(thickness 0.1524)
				)
				(justify mirror)
			)
		)
		(duplicate_pad_numbers_are_jumpers no)
		(fp_line
			(start 0.508 -0.9398)
			(end 0.508 0.9398)
			(stroke
				(width 0.1524)
				(type default)
			)
			(layer "B.SilkS")
		)
		(fp_line
			(start -0.508 -0.9398)
			(end 0.508 -0.9398)
			(stroke
				(width 0.1524)
				(type default)
			)
			(layer "B.SilkS")
		)
		(fp_rect
			(start 0.508 0.9398)
			(end -0.508 -0.9398)
			(stroke
				(width 0)
				(type default)
			)
			(fill no)
			(layer "B.CrtYd")
		)
		(fp_rect
			(start 0.508 0.9398)
			(end -0.508 -0.9398)
			(stroke
				(width 0)
				(type default)
			)
			(fill no)
			(layer "B.Fab")
		)
		(pad "1" smd custom
			(at 0 -0.4445)
			(size 0.1397 0.1397)
			(layers "B.Cu" "B.Mask" "B.Paste")
			(net "SSD_ATNLED#7")
			(options
				(clearance outline)
				(anchor circle)
			)
			(primitives
				(gr_poly
					(pts
						(arc
							(start -0.1778 0.2794)
							(mid -0.249642 0.249642)
							(end -0.2794 0.1778)
						)
						(arc
							(start -0.2794 -0.1778)
							(mid -0.249642 -0.249642)
							(end -0.1778 -0.2794)
						)
						(arc
							(start 0.1778 -0.2794)
							(mid 0.249642 -0.249642)
							(end 0.2794 -0.1778)
						)
						(arc
							(start 0.2794 0.1778)
							(mid 0.249642 0.249642)
							(end 0.1778 0.2794)
						)
					)
					(width 0)
					(fill yes)
				)
			)
		)
		(pad "2" smd custom
			(at 0 0.4445)
			(size 0.1397 0.1397)
			(layers "B.Cu" "B.Mask" "B.Paste")
			(net "P3V3_STBY")
			(options
				(clearance outline)
				(anchor circle)
			)
			(primitives
				(gr_poly
					(pts
						(arc
							(start -0.1778 0.2794)
							(mid -0.249642 0.249642)
							(end -0.2794 0.1778)
						)
						(arc
							(start -0.2794 -0.1778)
							(mid -0.249642 -0.249642)
							(end -0.1778 -0.2794)
						)
						(arc
							(start 0.1778 -0.2794)
							(mid 0.249642 -0.249642)
							(end 0.2794 -0.1778)
						)
						(arc
							(start 0.2794 0.1778)
							(mid 0.249642 0.249642)
							(end 0.1778 0.2794)
						)
					)
					(width 0)
					(fill yes)
				)
			)
		)
	)
	(footprint ""
		(layer "B.Cu")
		(at 315.468 -55.372)
		(property "Reference" "PC183"
			(at 0 0 0)
			(layer "B.SilkS")
			(hide yes)
			(effects
				(font
					(size 1.27 1.27)
				)
				(justify mirror)
			)
		)
		(property "Value" "SC22U6D3V5MX-5-GP"
			(at 0.0762 -6.1214 0)
			(unlocked yes)
			(layer "B.Fab")
			(hide yes)
			(effects
				(font
					(size 1.016 1.016)
					(thickness 0.1524)
				)
				(justify mirror)
			)
		)
		(property "Device Type" "C805H56"
			(at 0.0762 -8.1534 0)
			(unlocked yes)
			(layer "B.Fab")
			(hide yes)
			(effects
				(font
					(size 1.016 1.016)
					(thickness 0.1524)
				)
				(justify mirror)
			)
		)
		(duplicate_pad_numbers_are_jumpers no)
		(fp_line
			(start -0.635 0)
			(end 0.635 0)
			(stroke
				(width 0.508)
				(type default)
			)
			(layer "B.SilkS")
		)
		(fp_rect
			(start 0.9652 1.778)
			(end -0.9652 -1.778)
			(stroke
				(width 0)
				(type default)
			)
			(fill no)
			(layer "B.CrtYd")
		)
		(fp_poly
			(pts
				(xy 0.9652 -1.778) (xy -0.9652 -1.778) (xy -0.9652 1.778) (xy 0.9652 1.778)
			)
			(stroke
				(width 0)
				(type default)
			)
			(fill no)
			(layer "B.Fab")
		)
		(pad "1" smd rect
			(at 0 -0.9652 180)
			(size 1.397 1.143)
			(layers "B.Cu" "B.Mask" "B.Paste")
			(net "P0V9_E")
		)
		(pad "2" smd rect
			(at 0 0.9652 180)
			(size 1.397 1.143)
			(layers "B.Cu" "B.Mask" "B.Paste")
			(net "GND")
		)
	)
)
